#ISCELL
  mstr_misc dns *
  *
#ISCELL
  pure_quanta quanta_title_block_c *
  *
#ISCELL
  pure_quanta_power universal_gnd *
  page193_i1
#ISCELL
  pure_quanta_power universal_gnd *
  page193_i10
#CELL
  pure_quanta q_cap *
  page193_i11
#CELL
  pure_quanta q_cap *
  page193_i12
#ISCELL
  pure_quanta_power universal_gnd *
  page193_i13
#CELL
  pure_quanta q_res *
  page193_i14
#CELL
  pure_quanta q_cap *
  page193_i15
#ISCELL
  pure_quanta_power universal_gnd *
  page193_i16
#CELL
  pure_quanta q_res *
  page193_i17
#ISCELL
  pure_quanta_power vcc_core *
  page193_i18
#ISCELL
  standard offpage *
  page193_i19
#CELL
  pure_quanta q_cap *
  page193_i2
#ISCELL
  standard offpage *
  page193_i20
#ISCELL
  pure_quanta_power vcc_core *
  page193_i21
#ISCELL
  pure_quanta_power universal_gnd *
  page193_i22
#CELL
  pure_quanta q_cap *
  page193_i23
#ISCELL
  standard offpage *
  page193_i24
#ISCELL
  standard offpage *
  page193_i25
#ISCELL
  pure_quanta_power vcc_core *
  page193_i26
#CELL
  pure_quanta q_res *
  page193_i27
#ISCELL
  pure_quanta_power universal_gnd *
  page193_i28
#CELL
  pure_quanta q_cap *
  page193_i29
#ISCELL
  pure_quanta_power universal_gnd *
  page193_i3
#ISCELL
  pure_quanta_power vcc_core *
  page193_i30
#CELL
  pure_quanta isl99390frztr5935 *
  page193_i31
#ISCELL
  pure_quanta_power universal_gnd *
  page193_i32
#ISCELL
  pure_quanta_power universal_gnd *
  page193_i33
#CELL
  pure_quanta q_cap *
  page193_i34
#ISCELL
  pure_quanta_power universal_gnd *
  page193_i35
#CELL
  pure_quanta q_res *
  page193_i36
#CELL
  pure_quanta q_cap *
  page193_i37
#CELL
  pure_quanta q_res *
  page193_i38
#ISCELL
  standard offpage *
  page193_i39
#CELL
  pure_quanta q_res *
  page193_i4
#CELL
  pure_quanta q_cap *
  page193_i40
#CELL
  pure_quanta q_res *
  page193_i41
#CELL
  pure_quanta q_cap *
  page193_i42
#CELL
  pure_quanta q_cap *
  page193_i43
#ISCELL
  pure_quanta_power universal_gnd *
  page193_i44
#CELL
  pure_quanta q_res *
  page193_i45
#CELL
  pure_quanta q_cap *
  page193_i46
#ISCELL
  pure_quanta_power universal_gnd *
  page193_i47
#CELL
  pure_quanta q_cap *
  page193_i48
#ISCELL
  pure_quanta_power vcc_core *
  page193_i49
#ISCELL
  standard offpage *
  page193_i5
#CELL
  pure_quanta q_cap *
  page193_i50
#CELL
  pure_quanta q_res *
  page193_i51
#CELL
  pure_quanta q_cap *
  page193_i52
#CELL
  pure_quanta q_cap *
  page193_i53
#CELL
  pure_quanta q_cap *
  page193_i54
#ISCELL
  standard offpage *
  page193_i55
#ISCELL
  pure_quanta_power universal_gnd *
  page193_i56
#CELL
  pure_quanta q_cap *
  page193_i57
#CELL
  pure_quanta q_cap *
  page193_i58
#ISCELL
  pure_quanta_power vcc_core *
  page193_i59
#ISCELL
  standard offpage *
  page193_i6
#CELL
  pure_quanta q_cap *
  page193_i60
#CELL
  pure_quanta q_inductor4p_14 *
  page193_i62
#ISCELL
  standard offpage *
  page193_i63
#CELL
  pure_quanta q_res *
  page193_i64
#CELL
  pure_quanta q_capp *
  page193_i65
#CELL
  pure_quanta q_capp *
  page193_i66
#CELL
  pure_quanta q_capp *
  page193_i67
#CELL
  pure_quanta q_cap *
  page193_i68
#ISCELL
  pure_quanta_power universal_gnd *
  page193_i69
#ISCELL
  standard offpage *
  page193_i7
#CELL
  pure_quanta q_cap *
  page193_i70
#ISCELL
  pure_quanta_power vcc_core *
  page193_i71
#ISCELL
  pure_quanta_power universal_gnd *
  page193_i72
#CELL
  pure_quanta q_capp *
  page193_i73
#CELL
  pure_quanta q_capp *
  page193_i74
#ISCELL
  pure_quanta_power vcc_core *
  page193_i75
#ISCELL
  pure_quanta_power universal_gnd *
  page193_i76
#CELL
  pure_quanta q_inductor4p_14 *
  page193_i77
#CELL
  pure_quanta q_inductor *
  page193_i79
#ISCELL
  standard offpage *
  page193_i8
#ISCELL
  standard offpage *
  page193_i80
#ISCELL
  pure_quanta_power universal_gnd *
  page193_i81
#CELL
  pure_quanta q_cap *
  page193_i82
#CELL
  pure_quanta q_cap *
  page193_i83
#ISCELL
  pure_quanta_power vcc_core *
  page193_i84
#CELL
  pure_quanta q_cap *
  page193_i85
#CELL
  pure_quanta q_cap *
  page193_i86
#CELL
  pure_quanta q_res *
  page193_i87
#ISCELL
  pure_quanta_power vcc_core *
  page193_i88
#CELL
  pure_quanta q_res *
  page193_i89
#ISCELL
  pure_quanta_power universal_gnd *
  page193_i9
#CELL
  pure_quanta q_res *
  page193_i90
#CELL
  pure_quanta isl99390frztr5935 *
  page193_i91
#CELL
  pure_quanta q_capp *
  page193_i92
#CELL
  pure_quanta q_capp *
  page193_i93
